(kicad_pcb
	(version 20260206)
	(generator "pcbnew")
	(generator_version "10.0")
	(general
		(thickness 1.6)
		(legacy_teardrops no)
	)
	(paper "A4")
	(title_block
		(title "Wiwynn_Tioga_Pass_MB.brd")
		(comment 1 "Tioga Pass / footprint 2254 of 4770 (U5D1), pads 1645-1752 of 3647")
	)
	(layers
		(0 "F.Cu" signal "TOP")
		(4 "In1.Cu" signal "L2GND")
		(6 "In2.Cu" signal "L3")
		(8 "In3.Cu" signal "L4GND")
		(10 "In4.Cu" signal "L5")
		(12 "In5.Cu" signal "L6GND")
		(14 "In6.Cu" signal "L7VCC")
		(16 "In7.Cu" signal "L8VCC")
		(18 "In8.Cu" signal "L9GND")
		(20 "In9.Cu" signal "L10")
		(22 "In10.Cu" signal "L11GND")
		(24 "In11.Cu" signal "L12")
		(26 "In12.Cu" signal "L13GND")
		(2 "B.Cu" signal "BOTTOM")
		(9 "F.Adhes" user "F.Adhesive")
		(11 "B.Adhes" user "B.Adhesive")
		(13 "F.Paste" user "Package Geometry/Pastemask Top")
		(15 "B.Paste" user "Package Geometry/Pastemask Bottom")
		(5 "F.SilkS" user "Ref Des/Silkscreen Top")
		(7 "B.SilkS" user "Ref Des/Silkscreen Bottom")
		(1 "F.Mask" user "Board Geometry/Soldermask Top")
		(3 "B.Mask" user "Board Geometry/Soldermask Bottom")
		(17 "Dwgs.User" user "User.Drawings")
		(19 "Cmts.User" user "User.Comments")
		(21 "Eco1.User" user "User.Eco1")
		(23 "Eco2.User" user "User.Eco2")
		(25 "Edge.Cuts" user "Board Geometry/Outline")
		(27 "Margin" user)
		(31 "F.CrtYd" user "Package Geometry/Place Bound Top")
		(29 "B.CrtYd" user "Package Geometry/Place Bound Bottom")
		(35 "F.Fab" user "Ref Des/Assembly Top")
		(33 "B.Fab" user "Ref Des/Assembly Bottom")
	)
	(footprint ""
		(layer "F.Cu")
		(at 270.000222 -76.550012 180)
		(property "Reference" "U5D1"
			(at 19.124422 31.601918 0)
			(unlocked yes)
			(layer "F.SilkS")
			(effects
				(font
					(size 0.7874 0.5842)
					(thickness 0.1524)
				)
			)
		)
		(property "Value" ""
			(at 0 0 180)
			(layer "F.Fab")
			(effects
				(font
					(size 1.27 1.27)
				)
			)
		)
		(duplicate_pad_numbers_are_jumpers no)
		(pad "CN70" smd circle
			(at 23.514558 8.758428)
			(size 0.4318 0.4318)
			(layers "F.Cu" "F.Mask" "F.Paste")
			(net "M_F_DQS_DN<8>")
		)
		(pad "CN74" smd circle
			(at 26.948384 8.758428)
			(size 0.4318 0.4318)
			(layers "F.Cu" "F.Mask" "F.Paste")
			(net "M_F_DQ<4>")
		)
		(pad "CN76" smd circle
			(at 28.665424 8.758428)
			(size 0.4318 0.4318)
			(layers "F.Cu" "F.Mask" "F.Paste")
			(net "M_F_DQ<1>")
		)
		(pad "CN78" smd circle
			(at 30.382464 8.758428)
			(size 0.4318 0.4318)
			(layers "F.Cu" "F.Mask" "F.Paste")
			(net "GND")
		)
		(pad "CN80" smd circle
			(at 32.099504 8.758428)
			(size 0.4318 0.4318)
			(layers "F.Cu" "F.Mask" "F.Paste")
			(net "M_E_DQS_DN<9>")
		)
		(pad "CN82" smd circle
			(at 33.816544 8.758428)
			(size 0.4318 0.4318)
			(layers "F.Cu" "F.Mask" "F.Paste")
			(net "M_E_DQ<7>")
		)
		(pad "CN84" smd circle
			(at 35.533584 8.758428)
			(size 0.4318 0.4318)
			(layers "F.Cu" "F.Mask" "F.Paste")
			(net "M_D_DQ<0>")
		)
		(pad "CN86" smd custom
			(at 37.250624 8.758428 270)
			(size 0.10795 0.10795)
			(layers "F.Cu" "F.Mask" "F.Paste")
			(net "M_D_DQ<1>")
			(options
				(clearance outline)
				(anchor circle)
			)
			(primitives
				(gr_poly
					(pts
						(arc
							(start 0.2159 -0.0381)
							(mid 0 -0.254)
							(end -0.2159 -0.0381)
						)
						(arc
							(start -0.2159 0.0381)
							(mid 0 0.254)
							(end 0.2159 0.0381)
						)
					)
					(width 0)
					(fill yes)
				)
			)
		)
		(pad "CP1" smd custom
			(at -37.250624 11.053572 90)
			(size 0.10795 0.10795)
			(layers "F.Cu" "F.Mask" "F.Paste")
			(net "GND")
			(options
				(clearance outline)
				(anchor circle)
			)
			(primitives
				(gr_poly
					(pts
						(arc
							(start 0.2159 -0.0381)
							(mid 0 -0.254)
							(end -0.2159 -0.0381)
						)
						(arc
							(start -0.2159 0.0381)
							(mid 0 0.254)
							(end 0.2159 0.0381)
						)
					)
					(width 0)
					(fill yes)
				)
			)
		)
		(pad "CP3" smd circle
			(at -35.533584 11.053572)
			(size 0.4318 0.4318)
			(layers "F.Cu" "F.Mask" "F.Paste")
			(net "P3E_CPU0_PE2_SS_TXP<3>")
		)
		(pad "CP5" smd circle
			(at -33.816544 11.053572)
			(size 0.4318 0.4318)
			(layers "F.Cu" "F.Mask" "F.Paste")
			(net "DMI_CPU0_PCH_TX_DN<3>")
		)
		(pad "CP7" smd circle
			(at -32.099504 11.053572)
			(size 0.4318 0.4318)
			(layers "F.Cu" "F.Mask" "F.Paste")
			(net "P3E_CPU0_PE2_SS_RXN<2>")
		)
		(pad "CP9" smd circle
			(at -30.382464 11.053572)
			(size 0.4318 0.4318)
			(layers "F.Cu" "F.Mask" "F.Paste")
			(net "P3E_CPU0_PE2_SS_RXN<1>")
		)
		(pad "CP11" smd circle
			(at -28.665424 11.053572)
			(size 0.4318 0.4318)
			(layers "F.Cu" "F.Mask" "F.Paste")
			(net "DMI_CPU0_PCH_RX_C_DP<2>")
		)
		(pad "CP13" smd circle
			(at -26.948384 11.053572)
			(size 0.4318 0.4318)
			(layers "F.Cu" "F.Mask" "F.Paste")
			(net "PVCCIO_CPU0")
		)
		(pad "CP19" smd circle
			(at -21.797518 11.053572)
			(size 0.4318 0.4318)
			(layers "F.Cu" "F.Mask" "F.Paste")
			(net "GND")
		)
		(pad "CP21" smd circle
			(at -20.080478 11.053572)
			(size 0.4318 0.4318)
			(layers "F.Cu" "F.Mask" "F.Paste")
			(net "GND")
		)
		(pad "CP23" smd circle
			(at -18.363438 11.053572)
			(size 0.4318 0.4318)
			(layers "F.Cu" "F.Mask" "F.Paste")
			(net "PVCCMCP_CPU0")
		)
		(pad "CP25" smd circle
			(at -16.646398 11.053572)
			(size 0.4318 0.4318)
			(layers "F.Cu" "F.Mask" "F.Paste")
			(net "GND")
		)
		(pad "CP27" smd circle
			(at -14.929612 11.053572)
			(size 0.4318 0.4318)
			(layers "F.Cu" "F.Mask" "F.Paste")
			(net "CLK_100M_CPU0_BCLK1_DP")
		)
		(pad "CP29" smd circle
			(at -13.212572 11.053572)
			(size 0.4318 0.4318)
			(layers "F.Cu" "F.Mask" "F.Paste")
			(net "A_CPU0_PE3_RBIAS")
		)
		(pad "CP31" smd circle
			(at -11.495532 11.053572)
			(size 0.4318 0.4318)
			(layers "F.Cu" "F.Mask" "F.Paste")
			(net "TP_CPU0_RSVD_73")
		)
		(pad "CP33" smd circle
			(at -9.778492 11.053572)
			(size 0.4318 0.4318)
			(layers "F.Cu" "F.Mask" "F.Paste")
			(net "PVCCIN_CPU0")
		)
		(pad "CP55" smd circle
			(at 10.637012 9.253474)
			(size 0.508 0.508)
			(layers "F.Cu" "F.Mask" "F.Paste")
			(net "PVCCIN_CPU0")
		)
		(pad "CP57" smd circle
			(at 12.354052 9.253474)
			(size 0.4318 0.4318)
			(layers "F.Cu" "F.Mask" "F.Paste")
			(net "PVCCIN_CPU0")
		)
		(pad "CP59" smd circle
			(at 14.071092 9.253474)
			(size 0.4318 0.4318)
			(layers "F.Cu" "F.Mask" "F.Paste")
			(net "GND")
		)
		(pad "CP61" smd circle
			(at 15.787878 9.253474)
			(size 0.4318 0.4318)
			(layers "F.Cu" "F.Mask" "F.Paste")
			(net "M_D_CPU_VREF")
		)
		(pad "CP63" smd circle
			(at 17.504918 9.253474)
			(size 0.4318 0.4318)
			(layers "F.Cu" "F.Mask" "F.Paste")
			(net "M_F_DQ<26>")
		)
		(pad "CP65" smd circle
			(at 19.221958 9.253474)
			(size 0.4318 0.4318)
			(layers "F.Cu" "F.Mask" "F.Paste")
			(net "M_F_DQS_DN<12>")
		)
		(pad "CP67" smd circle
			(at 20.938998 9.253474)
			(size 0.4318 0.4318)
			(layers "F.Cu" "F.Mask" "F.Paste")
			(net "M_F_DQ<28>")
		)
		(pad "CP69" smd circle
			(at 22.656038 9.253474)
			(size 0.4318 0.4318)
			(layers "F.Cu" "F.Mask" "F.Paste")
			(net "GND")
		)
		(pad "CP73" smd circle
			(at 26.090118 9.253474)
			(size 0.4318 0.4318)
			(layers "F.Cu" "F.Mask" "F.Paste")
			(net "GND")
		)
		(pad "CP75" smd circle
			(at 27.806904 9.253474)
			(size 0.4318 0.4318)
			(layers "F.Cu" "F.Mask" "F.Paste")
			(net "GND")
		)
		(pad "CP77" smd circle
			(at 29.523944 9.253474)
			(size 0.4318 0.4318)
			(layers "F.Cu" "F.Mask" "F.Paste")
			(net "M_F_DQS_DN<0>")
		)
		(pad "CP79" smd circle
			(at 31.240984 9.253474)
			(size 0.4318 0.4318)
			(layers "F.Cu" "F.Mask" "F.Paste")
			(net "M_E_DQS_DP<9>")
		)
		(pad "CP81" smd circle
			(at 32.958024 9.253474)
			(size 0.4318 0.4318)
			(layers "F.Cu" "F.Mask" "F.Paste")
			(net "GND")
		)
		(pad "CP83" smd circle
			(at 34.675064 9.253474)
			(size 0.4318 0.4318)
			(layers "F.Cu" "F.Mask" "F.Paste")
			(net "GND")
		)
		(pad "CP85" smd circle
			(at 36.392104 9.253474)
			(size 0.4318 0.4318)
			(layers "F.Cu" "F.Mask" "F.Paste")
			(net "M_D_DQS_DP<9>")
		)
		(pad "CR2" smd circle
			(at -36.392104 11.549126)
			(size 0.4318 0.4318)
			(layers "F.Cu" "F.Mask" "F.Paste")
			(net "P3E_CPU0_PE2_SS_TXP<2>")
		)
		(pad "CR4" smd circle
			(at -34.675064 11.549126)
			(size 0.4318 0.4318)
			(layers "F.Cu" "F.Mask" "F.Paste")
			(net "DMI_CPU0_PCH_TX_DP<3>")
		)
		(pad "CR6" smd circle
			(at -32.958024 11.549126)
			(size 0.4318 0.4318)
			(layers "F.Cu" "F.Mask" "F.Paste")
			(net "GND")
		)
		(pad "CR8" smd circle
			(at -31.240984 11.549126)
			(size 0.4318 0.4318)
			(layers "F.Cu" "F.Mask" "F.Paste")
			(net "P3E_CPU0_PE2_SS_RXP<0>")
		)
		(pad "CR10" smd circle
			(at -29.523944 11.549126)
			(size 0.4318 0.4318)
			(layers "F.Cu" "F.Mask" "F.Paste")
			(net "GND")
		)
		(pad "CR12" smd circle
			(at -27.806904 11.549126)
			(size 0.4318 0.4318)
			(layers "F.Cu" "F.Mask" "F.Paste")
			(net "DMI_CPU0_PCH_RX_C_DN<2>")
		)
		(pad "CR14" smd circle
			(at -26.090118 11.549126)
			(size 0.4318 0.4318)
			(layers "F.Cu" "F.Mask" "F.Paste")
			(net "TP_CPU0_UPI2_RSVD_DE16")
		)
		(pad "CR18" smd circle
			(at -22.656038 11.549126)
			(size 0.4318 0.4318)
			(layers "F.Cu" "F.Mask" "F.Paste")
			(net "GND")
		)
		(pad "CR20" smd circle
			(at -20.938998 11.549126)
			(size 0.4318 0.4318)
			(layers "F.Cu" "F.Mask" "F.Paste")
			(net "GND")
		)
		(pad "CR22" smd circle
			(at -19.221958 11.549126)
			(size 0.4318 0.4318)
			(layers "F.Cu" "F.Mask" "F.Paste")
			(net "GND")
		)
		(pad "CR24" smd circle
			(at -17.504918 11.549126)
			(size 0.4318 0.4318)
			(layers "F.Cu" "F.Mask" "F.Paste")
			(net "GND")
		)
		(pad "CR26" smd circle
			(at -15.787878 11.549126)
			(size 0.4318 0.4318)
			(layers "F.Cu" "F.Mask" "F.Paste")
			(net "CLK_100M_CPU0_BCLK1_DN")
		)
		(pad "CR28" smd circle
			(at -14.071092 11.549126)
			(size 0.4318 0.4318)
			(layers "F.Cu" "F.Mask" "F.Paste")
			(net "PWRGD_CPU0_DRAMPWROK_DEF_G")
		)
		(pad "CR30" smd circle
			(at -12.354052 11.549126)
			(size 0.4318 0.4318)
			(layers "F.Cu" "F.Mask" "F.Paste")
			(net "A_CPU0_PE3_RBIAS")
		)
		(pad "CR32" smd circle
			(at -10.637012 11.549126)
			(size 0.4318 0.4318)
			(layers "F.Cu" "F.Mask" "F.Paste")
			(net "GND")
		)
		(pad "CR34" smd circle
			(at -8.919972 11.549126)
			(size 0.4318 0.4318)
			(layers "F.Cu" "F.Mask" "F.Paste")
			(net "PVCCIN_CPU0")
		)
		(pad "CR54" smd circle
			(at 9.778492 9.749028)
			(size 0.508 0.508)
			(layers "F.Cu" "F.Mask" "F.Paste")
			(net "PVCCIN_CPU0")
		)
		(pad "CR56" smd circle
			(at 11.495532 9.749028)
			(size 0.4318 0.4318)
			(layers "F.Cu" "F.Mask" "F.Paste")
			(net "PVCCIN_CPU0")
		)
		(pad "CR58" smd circle
			(at 13.212572 9.749028)
			(size 0.4318 0.4318)
			(layers "F.Cu" "F.Mask" "F.Paste")
			(net "GND")
		)
		(pad "CR60" smd circle
			(at 14.929612 9.749028)
			(size 0.4318 0.4318)
			(layers "F.Cu" "F.Mask" "F.Paste")
			(net "TP_CPU0_RSVD_72")
		)
		(pad "CR62" smd circle
			(at 16.646398 9.749028)
			(size 0.4318 0.4318)
			(layers "F.Cu" "F.Mask" "F.Paste")
			(net "GND")
		)
		(pad "CR64" smd circle
			(at 18.363438 9.749028)
			(size 0.4318 0.4318)
			(layers "F.Cu" "F.Mask" "F.Paste")
			(net "GND")
		)
		(pad "CR66" smd circle
			(at 20.080478 9.749028)
			(size 0.4318 0.4318)
			(layers "F.Cu" "F.Mask" "F.Paste")
			(net "GND")
		)
		(pad "CR68" smd circle
			(at 21.797518 9.749028)
			(size 0.4318 0.4318)
			(layers "F.Cu" "F.Mask" "F.Paste")
			(net "GND")
		)
		(pad "CR74" smd circle
			(at 26.948384 9.749028)
			(size 0.4318 0.4318)
			(layers "F.Cu" "F.Mask" "F.Paste")
			(net "M_F_DQ<0>")
		)
		(pad "CR76" smd circle
			(at 28.665424 9.749028)
			(size 0.4318 0.4318)
			(layers "F.Cu" "F.Mask" "F.Paste")
			(net "M_F_DQS_DP<0>")
		)
		(pad "CR78" smd circle
			(at 30.382464 9.749028)
			(size 0.4318 0.4318)
			(layers "F.Cu" "F.Mask" "F.Paste")
			(net "GND")
		)
		(pad "CR80" smd circle
			(at 32.099504 9.749028)
			(size 0.4318 0.4318)
			(layers "F.Cu" "F.Mask" "F.Paste")
			(net "M_E_DQ<6>")
		)
		(pad "CR82" smd circle
			(at 33.816544 9.749028)
			(size 0.4318 0.4318)
			(layers "F.Cu" "F.Mask" "F.Paste")
			(net "M_E_DQ<3>")
		)
		(pad "CR84" smd circle
			(at 35.533584 9.749028)
			(size 0.4318 0.4318)
			(layers "F.Cu" "F.Mask" "F.Paste")
			(net "M_D_DQS_DN<9>")
		)
		(pad "CR86" smd custom
			(at 37.250624 9.749028 270)
			(size 0.10795 0.10795)
			(layers "F.Cu" "F.Mask" "F.Paste")
			(net "GND")
			(options
				(clearance outline)
				(anchor circle)
			)
			(primitives
				(gr_poly
					(pts
						(arc
							(start 0.2159 -0.0381)
							(mid 0 -0.254)
							(end -0.2159 -0.0381)
						)
						(arc
							(start -0.2159 0.0381)
							(mid 0 0.254)
							(end 0.2159 0.0381)
						)
					)
					(width 0)
					(fill yes)
				)
			)
		)
		(pad "CT1" smd custom
			(at -37.250624 12.044172 90)
			(size 0.10795 0.10795)
			(layers "F.Cu" "F.Mask" "F.Paste")
			(net "P3E_CPU0_PE2_SS_TXN<2>")
			(options
				(clearance outline)
				(anchor circle)
			)
			(primitives
				(gr_poly
					(pts
						(arc
							(start 0.2159 -0.0381)
							(mid 0 -0.254)
							(end -0.2159 -0.0381)
						)
						(arc
							(start -0.2159 0.0381)
							(mid 0 0.254)
							(end 0.2159 0.0381)
						)
					)
					(width 0)
					(fill yes)
				)
			)
		)
		(pad "CT3" smd circle
			(at -35.533584 12.044172)
			(size 0.4318 0.4318)
			(layers "F.Cu" "F.Mask" "F.Paste")
			(net "P3E_CPU0_PE2_SS_TXN<3>")
		)
		(pad "CT5" smd circle
			(at -33.816544 12.044172)
			(size 0.4318 0.4318)
			(layers "F.Cu" "F.Mask" "F.Paste")
			(net "TP_CPU0_RSVD_70")
		)
		(pad "CT7" smd circle
			(at -32.099504 12.044172)
			(size 0.4318 0.4318)
			(layers "F.Cu" "F.Mask" "F.Paste")
			(net "GND")
		)
		(pad "CT9" smd circle
			(at -30.382464 12.044172)
			(size 0.4318 0.4318)
			(layers "F.Cu" "F.Mask" "F.Paste")
			(net "P3E_CPU0_PE2_SS_RXN<0>")
		)
		(pad "CT11" smd circle
			(at -28.665424 12.044172)
			(size 0.4318 0.4318)
			(layers "F.Cu" "F.Mask" "F.Paste")
			(net "DMI_CPU0_PCH_RX_C_DN<3>")
		)
		(pad "CT13" smd circle
			(at -26.948384 12.044172)
			(size 0.4318 0.4318)
			(layers "F.Cu" "F.Mask" "F.Paste")
			(net "GND")
		)
		(pad "CT19" smd circle
			(at -21.797518 12.044172)
			(size 0.4318 0.4318)
			(layers "F.Cu" "F.Mask" "F.Paste")
			(net "GND")
		)
		(pad "CT21" smd circle
			(at -20.080478 12.044172)
			(size 0.4318 0.4318)
			(layers "F.Cu" "F.Mask" "F.Paste")
			(net "GND")
		)
		(pad "CT23" smd circle
			(at -18.363438 12.044172)
			(size 0.4318 0.4318)
			(layers "F.Cu" "F.Mask" "F.Paste")
			(net "PVCCMCP_CPU0")
		)
		(pad "CT25" smd circle
			(at -16.646398 12.044172)
			(size 0.4318 0.4318)
			(layers "F.Cu" "F.Mask" "F.Paste")
			(net "CLK_100M_CPU0_BCLK2_DN")
		)
		(pad "CT27" smd circle
			(at -14.929612 12.044172)
			(size 0.4318 0.4318)
			(layers "F.Cu" "F.Mask" "F.Paste")
			(net "GND")
		)
		(pad "CT29" smd circle
			(at -13.212572 12.044172)
			(size 0.4318 0.4318)
			(layers "F.Cu" "F.Mask" "F.Paste")
			(net "GND")
		)
		(pad "CT31" smd circle
			(at -11.495532 12.044172)
			(size 0.4318 0.4318)
			(layers "F.Cu" "F.Mask" "F.Paste")
			(net "A_CPU0_MCP01_RBIAS")
		)
		(pad "CT33" smd circle
			(at -9.778492 12.044172)
			(size 0.4318 0.4318)
			(layers "F.Cu" "F.Mask" "F.Paste")
			(net "GND")
		)
		(pad "CT35" smd circle
			(at -8.061452 12.044172)
			(size 0.4318 0.4318)
			(layers "F.Cu" "F.Mask" "F.Paste")
			(net "GND")
		)
		(pad "CT37" smd circle
			(at -6.344412 12.044172)
			(size 0.4318 0.4318)
			(layers "F.Cu" "F.Mask" "F.Paste")
			(net "PVCCIN_CPU0")
		)
		(pad "CT39" smd circle
			(at -4.627626 12.044172)
			(size 0.4318 0.4318)
			(layers "F.Cu" "F.Mask" "F.Paste")
			(net "PVCCIN_CPU0")
		)
		(pad "CT41" smd circle
			(at -2.910586 12.044172)
			(size 0.4318 0.4318)
			(layers "F.Cu" "F.Mask" "F.Paste")
			(net "PVCCIN_CPU0")
		)
		(pad "CT53" smd circle
			(at 8.919972 10.244074)
			(size 0.508 0.508)
			(layers "F.Cu" "F.Mask" "F.Paste")
			(net "PVCCIN_CPU0")
		)
		(pad "CT55" smd circle
			(at 10.637012 10.244074)
			(size 0.4318 0.4318)
			(layers "F.Cu" "F.Mask" "F.Paste")
			(net "PVCCIN_CPU0")
		)
		(pad "CT57" smd circle
			(at 12.354052 10.244074)
			(size 0.4318 0.4318)
			(layers "F.Cu" "F.Mask" "F.Paste")
			(net "GND")
		)
		(pad "CT59" smd circle
			(at 14.071092 10.244074)
			(size 0.4318 0.4318)
			(layers "F.Cu" "F.Mask" "F.Paste")
			(net "SMB_PIROM_CPU0_SCL")
		)
		(pad "CT61" smd circle
			(at 15.787878 10.244074)
			(size 0.4318 0.4318)
			(layers "F.Cu" "F.Mask" "F.Paste")
			(net "M_E_CPU_VREF")
		)
		(pad "CT63" smd circle
			(at 17.504918 10.244074)
			(size 0.4318 0.4318)
			(layers "F.Cu" "F.Mask" "F.Paste")
			(net "M_F_DQ<27>")
		)
		(pad "CT65" smd circle
			(at 19.221958 10.244074)
			(size 0.4318 0.4318)
			(layers "F.Cu" "F.Mask" "F.Paste")
			(net "M_F_DQS_DP<3>")
		)
		(pad "CT67" smd circle
			(at 20.938998 10.244074)
			(size 0.4318 0.4318)
			(layers "F.Cu" "F.Mask" "F.Paste")
			(net "M_F_DQ<29>")
		)
		(pad "CT69" smd circle
			(at 22.656038 10.244074)
			(size 0.4318 0.4318)
			(layers "F.Cu" "F.Mask" "F.Paste")
			(net "TP_CPU0_RSVD_69")
		)
		(pad "CT73" smd circle
			(at 26.090118 10.244074)
			(size 0.4318 0.4318)
			(layers "F.Cu" "F.Mask" "F.Paste")
			(net "GND")
		)
		(pad "CT75" smd circle
			(at 27.806904 10.244074)
			(size 0.4318 0.4318)
			(layers "F.Cu" "F.Mask" "F.Paste")
			(net "M_F_DQS_DN<9>")
		)
		(pad "CT77" smd circle
			(at 29.523944 10.244074)
			(size 0.4318 0.4318)
			(layers "F.Cu" "F.Mask" "F.Paste")
			(net "M_F_DQ<7>")
		)
		(pad "CT79" smd circle
			(at 31.240984 10.244074)
			(size 0.4318 0.4318)
			(layers "F.Cu" "F.Mask" "F.Paste")
			(net "GND")
		)
		(pad "CT81" smd circle
			(at 32.958024 10.244074)
			(size 0.4318 0.4318)
			(layers "F.Cu" "F.Mask" "F.Paste")
			(net "M_E_DQ<2>")
		)
		(pad "CT83" smd circle
			(at 34.675064 10.244074)
			(size 0.4318 0.4318)
			(layers "F.Cu" "F.Mask" "F.Paste")
			(net "GND")
		)
		(pad "CT85" smd circle
			(at 36.392104 10.244074)
			(size 0.4318 0.4318)
			(layers "F.Cu" "F.Mask" "F.Paste")
			(net "GND")
		)
		(pad "CU2" smd circle
			(at -36.392104 12.539726)
			(size 0.4318 0.4318)
			(layers "F.Cu" "F.Mask" "F.Paste")
			(net "P3E_CPU0_PE2_SS_TXP<1>")
		)
		(pad "CU4" smd circle
			(at -34.675064 12.539726)
			(size 0.4318 0.4318)
			(layers "F.Cu" "F.Mask" "F.Paste")
			(net "GND")
		)
		(pad "CU6" smd circle
			(at -32.958024 12.539726)
			(size 0.4318 0.4318)
			(layers "F.Cu" "F.Mask" "F.Paste")
			(net "TP_CPU0_RSVD_67")
		)
		(pad "CU8" smd circle
			(at -31.240984 12.539726)
			(size 0.4318 0.4318)
			(layers "F.Cu" "F.Mask" "F.Paste")
			(net "P3E_CPU0_PE1_SS_RXP<0>")
		)
	)
)
